# T6G (Grand Teton) — schematic netlist excerpt (pin names and nets, part order shuffled) for the footprints in the layout excerpt that follows; sources: Cadence DE-HDL packaged netlist, KiCad conversion of 04192023_DAF0TMB3IC0_F0TG_MB_C_brd_V02_OCP.brd

R4204  Q_RES  1K 1% EMPTY  pkg 0402LF  page 235 : A = P3V3_AUX ; B = U271_1_ADD0
R8038  Q_RES  10K 1% CHIP  pkg 0402LF  page 92 : A = P3V3_AUX ; B = PWRGD_CHGL_CPU0
R6714  Q_RES  1K 1% EMPTY  pkg 0201LF  page 320 : A = P1V8_CPU1_RT_1D ; B = RT_CPU1_P0_ADDR2

(kicad_pcb
	(version 20260206)
	(generator "pcbnew")
	(generator_version "10.0")
	(general
		(thickness 1.6)
		(legacy_teardrops no)
	)
	(paper "A4")
	(title_block
		(title "04192023_DAF0TMB3IC0_F0TG_MB_C_brd_V02_OCP.brd")
		(comment 1 "Grand Teton / footprints 4590-4592 of 8354")
	)
	(layers
		(0 "F.Cu" signal "TOP")
		(4 "In1.Cu" signal "GND")
		(6 "In2.Cu" signal "IN1")
		(8 "In3.Cu" signal "GND1")
		(10 "In4.Cu" signal "IN2")
		(12 "In5.Cu" signal "GND2")
		(14 "In6.Cu" signal "IN3")
		(16 "In7.Cu" signal "GND3")
		(18 "In8.Cu" signal "VCC")
		(20 "In9.Cu" signal "VCC1")
		(22 "In10.Cu" signal "GND4")
		(24 "In11.Cu" signal "IN4")
		(26 "In12.Cu" signal "GND5")
		(28 "In13.Cu" signal "IN5")
		(30 "In14.Cu" signal "GND6")
		(32 "In15.Cu" signal "IN6")
		(34 "In16.Cu" signal "GND7")
		(2 "B.Cu" signal "BOTTOM")
		(9 "F.Adhes" user "F.Adhesive")
		(11 "B.Adhes" user "B.Adhesive")
		(13 "F.Paste" user "Package Geometry/Pastemask Top")
		(15 "B.Paste" user "Package Geometry/Pastemask Bottom")
		(5 "F.SilkS" user "Ref Des/Silkscreen Top")
		(7 "B.SilkS" user "Ref Des/Silkscreen Bottom")
		(1 "F.Mask" user "Board Geometry/Soldermask Top")
		(3 "B.Mask" user "Board Geometry/Soldermask Bottom")
		(17 "Dwgs.User" user "User.Drawings")
		(19 "Cmts.User" user "User.Comments")
		(21 "Eco1.User" user "User.Eco1")
		(23 "Eco2.User" user "User.Eco2")
		(25 "Edge.Cuts" user "Board Geometry/Outline")
		(27 "Margin" user)
		(31 "F.CrtYd" user "Package Geometry/Place Bound Top")
		(29 "B.CrtYd" user "Package Geometry/Place Bound Bottom")
		(35 "F.Fab" user "Ref Des/Assembly Top")
		(33 "B.Fab" user "Ref Des/Assembly Bottom")
	)
	(footprint ""
		(layer "F.Cu")
		(at 206.756 -99.695 180)
		(property "Reference" "R8038"
			(at 0 0 180)
			(layer "F.SilkS")
			(hide yes)
			(effects
				(font
					(size 1.27 1.27)
				)
			)
		)
		(property "Value" ""
			(at 0 0 180)
			(layer "F.Fab")
			(effects
				(font
					(size 1.27 1.27)
				)
			)
		)
		(duplicate_pad_numbers_are_jumpers no)
		(fp_line
			(start 0.7874 0.4064)
			(end -0.7874 0.4064)
			(stroke
				(width 0.1524)
				(type default)
			)
			(layer "F.SilkS")
		)
		(fp_line
			(start 0.7874 -0.4064)
			(end 0.7874 0.4064)
			(stroke
				(width 0.1524)
				(type default)
			)
			(layer "F.SilkS")
		)
		(fp_line
			(start -0.7874 0.4064)
			(end -0.7874 -0.4064)
			(stroke
				(width 0.1524)
				(type default)
			)
			(layer "F.SilkS")
		)
		(fp_line
			(start -0.7874 -0.4064)
			(end 0.7874 -0.4064)
			(stroke
				(width 0.1524)
				(type default)
			)
			(layer "F.SilkS")
		)
		(fp_line
			(start 0.67945 0.3048)
			(end 0.120396 0.3048)
			(stroke
				(width 0.1)
				(type default)
			)
			(layer "F.Fab")
		)
		(fp_line
			(start 0.67945 -0.3048)
			(end 0.67945 0.3048)
			(stroke
				(width 0.1)
				(type default)
			)
			(layer "F.Fab")
		)
		(fp_line
			(start 0.12065 -0.2794)
			(end 0.12065 -0.3048)
			(stroke
				(width 0.1)
				(type default)
			)
			(layer "F.Fab")
		)
		(fp_line
			(start 0.12065 -0.3048)
			(end 0.67945 -0.3048)
			(stroke
				(width 0.1)
				(type default)
			)
			(layer "F.Fab")
		)
		(fp_line
			(start 0.120396 0.3048)
			(end 0.120396 0.2794)
			(stroke
				(width 0.1)
				(type default)
			)
			(layer "F.Fab")
		)
		(fp_line
			(start 0.120396 0.2794)
			(end -0.12065 0.2794)
			(stroke
				(width 0.1)
				(type default)
			)
			(layer "F.Fab")
		)
		(fp_line
			(start -0.12065 0.3048)
			(end -0.67945 0.3048)
			(stroke
				(width 0.1)
				(type default)
			)
			(layer "F.Fab")
		)
		(fp_line
			(start -0.12065 0.2794)
			(end -0.12065 0.3048)
			(stroke
				(width 0.1)
				(type default)
			)
			(layer "F.Fab")
		)
		(fp_line
			(start -0.12065 -0.2794)
			(end 0.12065 -0.2794)
			(stroke
				(width 0.1)
				(type default)
			)
			(layer "F.Fab")
		)
		(fp_line
			(start -0.12065 -0.305054)
			(end -0.12065 -0.2794)
			(stroke
				(width 0.1)
				(type default)
			)
			(layer "F.Fab")
		)
		(fp_line
			(start -0.67945 0.3048)
			(end -0.67945 -0.305054)
			(stroke
				(width 0.1)
				(type default)
			)
			(layer "F.Fab")
		)
		(fp_line
			(start -0.67945 -0.305054)
			(end -0.12065 -0.305054)
			(stroke
				(width 0.1)
				(type default)
			)
			(layer "F.Fab")
		)
		(pad "1" smd circle
			(at -0.40005 0 180)
			(size 0 0)
			(layers "F.Cu" "F.Mask" "F.Paste")
			(net "P3V3_AUX")
		)
		(pad "2" smd circle
			(at 0.40005 0 180)
			(size 0 0)
			(layers "F.Cu" "F.Mask" "F.Paste")
			(net "PWRGD_CHGL_CPU0")
		)
	)
	(footprint ""
		(layer "F.Cu")
		(at 299.767498 -15.62481 180)
		(property "Reference" "R4204"
			(at 0 0 180)
			(layer "F.SilkS")
			(hide yes)
			(effects
				(font
					(size 1.27 1.27)
				)
			)
		)
		(property "Value" ""
			(at 0 0 180)
			(layer "F.Fab")
			(effects
				(font
					(size 1.27 1.27)
				)
			)
		)
		(duplicate_pad_numbers_are_jumpers no)
		(fp_line
			(start 0.7874 0.4064)
			(end -0.7874 0.4064)
			(stroke
				(width 0.1524)
				(type default)
			)
			(layer "F.SilkS")
		)
		(fp_line
			(start 0.7874 -0.4064)
			(end 0.7874 0.4064)
			(stroke
				(width 0.1524)
				(type default)
			)
			(layer "F.SilkS")
		)
		(fp_line
			(start -0.7874 0.4064)
			(end -0.7874 -0.4064)
			(stroke
				(width 0.1524)
				(type default)
			)
			(layer "F.SilkS")
		)
		(fp_line
			(start -0.7874 -0.4064)
			(end 0.7874 -0.4064)
			(stroke
				(width 0.1524)
				(type default)
			)
			(layer "F.SilkS")
		)
		(fp_line
			(start 0.67945 0.3048)
			(end 0.120396 0.3048)
			(stroke
				(width 0.1)
				(type default)
			)
			(layer "F.Fab")
		)
		(fp_line
			(start 0.67945 -0.3048)
			(end 0.67945 0.3048)
			(stroke
				(width 0.1)
				(type default)
			)
			(layer "F.Fab")
		)
		(fp_line
			(start 0.12065 -0.2794)
			(end 0.12065 -0.3048)
			(stroke
				(width 0.1)
				(type default)
			)
			(layer "F.Fab")
		)
		(fp_line
			(start 0.12065 -0.3048)
			(end 0.67945 -0.3048)
			(stroke
				(width 0.1)
				(type default)
			)
			(layer "F.Fab")
		)
		(fp_line
			(start 0.120396 0.3048)
			(end 0.120396 0.2794)
			(stroke
				(width 0.1)
				(type default)
			)
			(layer "F.Fab")
		)
		(fp_line
			(start 0.120396 0.2794)
			(end -0.12065 0.2794)
			(stroke
				(width 0.1)
				(type default)
			)
			(layer "F.Fab")
		)
		(fp_line
			(start -0.12065 0.3048)
			(end -0.67945 0.3048)
			(stroke
				(width 0.1)
				(type default)
			)
			(layer "F.Fab")
		)
		(fp_line
			(start -0.12065 0.2794)
			(end -0.12065 0.3048)
			(stroke
				(width 0.1)
				(type default)
			)
			(layer "F.Fab")
		)
		(fp_line
			(start -0.12065 -0.2794)
			(end 0.12065 -0.2794)
			(stroke
				(width 0.1)
				(type default)
			)
			(layer "F.Fab")
		)
		(fp_line
			(start -0.12065 -0.305054)
			(end -0.12065 -0.2794)
			(stroke
				(width 0.1)
				(type default)
			)
			(layer "F.Fab")
		)
		(fp_line
			(start -0.67945 0.3048)
			(end -0.67945 -0.305054)
			(stroke
				(width 0.1)
				(type default)
			)
			(layer "F.Fab")
		)
		(fp_line
			(start -0.67945 -0.305054)
			(end -0.12065 -0.305054)
			(stroke
				(width 0.1)
				(type default)
			)
			(layer "F.Fab")
		)
		(pad "1" smd circle
			(at -0.40005 0 180)
			(size 0 0)
			(layers "F.Cu" "F.Mask" "F.Paste")
			(net "P3V3_AUX")
		)
		(pad "2" smd circle
			(at 0.40005 0 180)
			(size 0 0)
			(layers "F.Cu" "F.Mask" "F.Paste")
			(net "U271_1_ADD0")
		)
	)
	(footprint ""
		(layer "F.Cu")
		(at 72.6948 -385.5212 90)
		(property "Reference" "R6714"
			(at 0 0 90)
			(layer "F.SilkS")
			(hide yes)
			(effects
				(font
					(size 1.27 1.27)
				)
			)
		)
		(property "Value" ""
			(at 0 0 90)
			(layer "F.Fab")
			(effects
				(font
					(size 1.27 1.27)
				)
			)
		)
		(duplicate_pad_numbers_are_jumpers no)
		(fp_line
			(start 0.32512 -0.175006)
			(end 0.32512 0.175006)
			(stroke
				(width 0.1)
				(type default)
			)
			(layer "F.Fab")
		)
		(fp_line
			(start -0.32512 -0.175006)
			(end 0.32512 -0.175006)
			(stroke
				(width 0.1)
				(type default)
			)
			(layer "F.Fab")
		)
		(fp_line
			(start 0.32512 0.175006)
			(end -0.32512 0.175006)
			(stroke
				(width 0.1)
				(type default)
			)
			(layer "F.Fab")
		)
		(fp_line
			(start -0.32512 0.175006)
			(end -0.32512 -0.175006)
			(stroke
				(width 0.1)
				(type default)
			)
			(layer "F.Fab")
		)
		(pad "1" smd rect
			(at -0.2667 0 90)
			(size 0.3048 0.381)
			(layers "F.Cu" "F.Mask" "F.Paste")
			(net "P1V8_CPU1_RT_1D")
		)
		(pad "2" smd rect
			(at 0.2667 0 270)
			(size 0.3048 0.381)
			(layers "F.Cu" "F.Mask" "F.Paste")
			(net "RT_CPU1_P0_ADDR2")
		)
	)
)
